# S9S_MB_2U (Grand Teton) — schematic netlist excerpt (pin names and nets, part order shuffled) for the footprints in the layout excerpt that follows; sources: Cadence DE-HDL packaged netlist, KiCad conversion of 03242023_DA0F0TMBIJ0_F0T_Motherboard_J_brd_V01_OCP.brd

R4741  Q_RES  0 5% CHIP  pkg 0402LF  page 227 : A = PRSNT_CABLE_SWB_B1_ISO_N ; B = PRSNT_CABLE_SWB_B1_ISO_R_N
C216  Q_CAP  47UF 4V 20% X6S  pkg C0805  page 74 : A = PVCCIN_CPU0 ; B = GND
R1870  Q_RES  10 1% CHIP  pkg 0402LF  page 202 : A = ESPI_LAD0_DATA_IO1 ; B = ESPI_LPC_LAD0_IO1

(kicad_pcb
	(version 20260206)
	(generator "pcbnew")
	(generator_version "10.0")
	(general
		(thickness 1.6)
		(legacy_teardrops no)
	)
	(paper "A4")
	(title_block
		(title "03242023_DA0F0TMBIJ0_F0T_Motherboard_J_brd_V01_OCP.brd")
		(comment 1 "Grand Teton / footprints 3050-3052 of 6105")
	)
	(layers
		(0 "F.Cu" signal "TOP")
		(4 "In1.Cu" signal "GND")
		(6 "In2.Cu" signal "IN1")
		(8 "In3.Cu" signal "GND1")
		(10 "In4.Cu" signal "IN2")
		(12 "In5.Cu" signal "GND2")
		(14 "In6.Cu" signal "IN3")
		(16 "In7.Cu" signal "GND3")
		(18 "In8.Cu" signal "VCC")
		(20 "In9.Cu" signal "VCC1")
		(22 "In10.Cu" signal "GND4")
		(24 "In11.Cu" signal "IN4")
		(26 "In12.Cu" signal "GND5")
		(28 "In13.Cu" signal "IN5")
		(30 "In14.Cu" signal "GND6")
		(32 "In15.Cu" signal "IN6")
		(34 "In16.Cu" signal "GND7")
		(2 "B.Cu" signal "BOTTOM")
		(9 "F.Adhes" user "F.Adhesive")
		(11 "B.Adhes" user "B.Adhesive")
		(13 "F.Paste" user "Package Geometry/Pastemask Top")
		(15 "B.Paste" user "Package Geometry/Pastemask Bottom")
		(5 "F.SilkS" user "Ref Des/Silkscreen Top")
		(7 "B.SilkS" user "Ref Des/Silkscreen Bottom")
		(1 "F.Mask" user "Board Geometry/Soldermask Top")
		(3 "B.Mask" user "Board Geometry/Soldermask Bottom")
		(17 "Dwgs.User" user "User.Drawings")
		(19 "Cmts.User" user "User.Comments")
		(21 "Eco1.User" user "User.Eco1")
		(23 "Eco2.User" user "User.Eco2")
		(25 "Edge.Cuts" user "Board Geometry/Outline")
		(27 "Margin" user)
		(31 "F.CrtYd" user "Package Geometry/Place Bound Top")
		(29 "B.CrtYd" user "Package Geometry/Place Bound Bottom")
		(35 "F.Fab" user "Ref Des/Assembly Top")
		(33 "B.Fab" user "Ref Des/Assembly Bottom")
	)
	(footprint ""
		(layer "F.Cu")
		(at 335.002124 -25.954482 -90)
		(property "Reference" "R1870"
			(at 0 0 270)
			(layer "F.SilkS")
			(hide yes)
			(effects
				(font
					(size 1.27 1.27)
				)
			)
		)
		(property "Value" ""
			(at 0 0 270)
			(layer "F.Fab")
			(effects
				(font
					(size 1.27 1.27)
				)
			)
		)
		(duplicate_pad_numbers_are_jumpers no)
		(fp_line
			(start -0.7874 0.4064)
			(end -0.7874 -0.4064)
			(stroke
				(width 0.1524)
				(type default)
			)
			(layer "F.SilkS")
		)
		(fp_line
			(start 0.7874 0.4064)
			(end -0.7874 0.4064)
			(stroke
				(width 0.1524)
				(type default)
			)
			(layer "F.SilkS")
		)
		(fp_line
			(start -0.7874 -0.4064)
			(end 0.7874 -0.4064)
			(stroke
				(width 0.1524)
				(type default)
			)
			(layer "F.SilkS")
		)
		(fp_line
			(start 0.7874 -0.4064)
			(end 0.7874 0.4064)
			(stroke
				(width 0.1524)
				(type default)
			)
			(layer "F.SilkS")
		)
		(fp_line
			(start -0.67945 0.3048)
			(end -0.67945 -0.305054)
			(stroke
				(width 0.1)
				(type default)
			)
			(layer "F.Fab")
		)
		(fp_line
			(start -0.12065 0.3048)
			(end -0.67945 0.3048)
			(stroke
				(width 0.1)
				(type default)
			)
			(layer "F.Fab")
		)
		(fp_line
			(start 0.120396 0.3048)
			(end 0.120396 0.2794)
			(stroke
				(width 0.1)
				(type default)
			)
			(layer "F.Fab")
		)
		(fp_line
			(start 0.67945 0.3048)
			(end 0.120396 0.3048)
			(stroke
				(width 0.1)
				(type default)
			)
			(layer "F.Fab")
		)
		(fp_line
			(start -0.12065 0.2794)
			(end -0.12065 0.3048)
			(stroke
				(width 0.1)
				(type default)
			)
			(layer "F.Fab")
		)
		(fp_line
			(start 0.120396 0.2794)
			(end -0.12065 0.2794)
			(stroke
				(width 0.1)
				(type default)
			)
			(layer "F.Fab")
		)
		(fp_line
			(start -0.12065 -0.2794)
			(end 0.12065 -0.2794)
			(stroke
				(width 0.1)
				(type default)
			)
			(layer "F.Fab")
		)
		(fp_line
			(start 0.12065 -0.2794)
			(end 0.12065 -0.3048)
			(stroke
				(width 0.1)
				(type default)
			)
			(layer "F.Fab")
		)
		(fp_line
			(start 0.12065 -0.3048)
			(end 0.67945 -0.3048)
			(stroke
				(width 0.1)
				(type default)
			)
			(layer "F.Fab")
		)
		(fp_line
			(start 0.67945 -0.3048)
			(end 0.67945 0.3048)
			(stroke
				(width 0.1)
				(type default)
			)
			(layer "F.Fab")
		)
		(fp_line
			(start -0.67945 -0.305054)
			(end -0.12065 -0.305054)
			(stroke
				(width 0.1)
				(type default)
			)
			(layer "F.Fab")
		)
		(fp_line
			(start -0.12065 -0.305054)
			(end -0.12065 -0.2794)
			(stroke
				(width 0.1)
				(type default)
			)
			(layer "F.Fab")
		)
		(pad "1" smd circle
			(at -0.40005 0 270)
			(size 0 0)
			(layers "F.Cu" "F.Mask" "F.Paste")
			(net "ESPI_LAD0_DATA_IO1")
		)
		(pad "2" smd circle
			(at 0.40005 0 270)
			(size 0 0)
			(layers "F.Cu" "F.Mask" "F.Paste")
			(net "ESPI_LPC_LAD0_IO1")
		)
	)
	(footprint ""
		(layer "F.Cu")
		(at 356.54488 -296.05478)
		(property "Reference" "C216"
			(at 0 0 0)
			(layer "F.SilkS")
			(hide yes)
			(effects
				(font
					(size 1.27 1.27)
				)
			)
		)
		(property "Value" ""
			(at 0 0 0)
			(layer "F.Fab")
			(effects
				(font
					(size 1.27 1.27)
				)
			)
		)
		(duplicate_pad_numbers_are_jumpers no)
		(fp_line
			(start -1.524 -0.762)
			(end 1.524 -0.762)
			(stroke
				(width 0.1524)
				(type default)
			)
			(layer "F.SilkS")
		)
		(fp_line
			(start -1.524 0.762)
			(end -1.524 -0.762)
			(stroke
				(width 0.1524)
				(type default)
			)
			(layer "F.SilkS")
		)
		(fp_line
			(start 1.524 -0.762)
			(end 1.524 0.762)
			(stroke
				(width 0.1524)
				(type default)
			)
			(layer "F.SilkS")
		)
		(fp_line
			(start 1.524 0.762)
			(end -1.524 0.762)
			(stroke
				(width 0.1524)
				(type default)
			)
			(layer "F.SilkS")
		)
		(fp_line
			(start -1.1049 -0.724916)
			(end -1.1049 0.724916)
			(stroke
				(width 0.1)
				(type default)
			)
			(layer "F.Fab")
		)
		(fp_line
			(start -1.1049 0.724916)
			(end 1.1049 0.724916)
			(stroke
				(width 0.1)
				(type default)
			)
			(layer "F.Fab")
		)
		(fp_line
			(start 1.1049 -0.724916)
			(end -1.1049 -0.724916)
			(stroke
				(width 0.1)
				(type default)
			)
			(layer "F.Fab")
		)
		(fp_line
			(start 1.1049 0.724916)
			(end 1.1049 -0.724916)
			(stroke
				(width 0.1)
				(type default)
			)
			(layer "F.Fab")
		)
		(pad "1" smd rect
			(at -0.889 0 180)
			(size 1.016 1.27)
			(layers "F.Cu" "F.Mask" "F.Paste")
			(net "PVCCIN_CPU0")
		)
		(pad "2" smd rect
			(at 0.889 0 180)
			(size 1.016 1.27)
			(layers "F.Cu" "F.Mask" "F.Paste")
			(net "GND")
		)
	)
	(footprint ""
		(layer "F.Cu")
		(at 24.892 -420.5732 180)
		(property "Reference" "R4741"
			(at 0 0 180)
			(layer "F.SilkS")
			(hide yes)
			(effects
				(font
					(size 1.27 1.27)
				)
			)
		)
		(property "Value" ""
			(at 0 0 180)
			(layer "F.Fab")
			(effects
				(font
					(size 1.27 1.27)
				)
			)
		)
		(duplicate_pad_numbers_are_jumpers no)
		(fp_line
			(start 0.7874 0.4064)
			(end -0.7874 0.4064)
			(stroke
				(width 0.1524)
				(type default)
			)
			(layer "F.SilkS")
		)
		(fp_line
			(start 0.7874 -0.4064)
			(end 0.7874 0.4064)
			(stroke
				(width 0.1524)
				(type default)
			)
			(layer "F.SilkS")
		)
		(fp_line
			(start -0.7874 0.4064)
			(end -0.7874 -0.4064)
			(stroke
				(width 0.1524)
				(type default)
			)
			(layer "F.SilkS")
		)
		(fp_line
			(start -0.7874 -0.4064)
			(end 0.7874 -0.4064)
			(stroke
				(width 0.1524)
				(type default)
			)
			(layer "F.SilkS")
		)
		(fp_line
			(start 0.67945 0.3048)
			(end 0.120396 0.3048)
			(stroke
				(width 0.1)
				(type default)
			)
			(layer "F.Fab")
		)
		(fp_line
			(start 0.67945 -0.3048)
			(end 0.67945 0.3048)
			(stroke
				(width 0.1)
				(type default)
			)
			(layer "F.Fab")
		)
		(fp_line
			(start 0.12065 -0.2794)
			(end 0.12065 -0.3048)
			(stroke
				(width 0.1)
				(type default)
			)
			(layer "F.Fab")
		)
		(fp_line
			(start 0.12065 -0.3048)
			(end 0.67945 -0.3048)
			(stroke
				(width 0.1)
				(type default)
			)
			(layer "F.Fab")
		)
		(fp_line
			(start 0.120396 0.3048)
			(end 0.120396 0.2794)
			(stroke
				(width 0.1)
				(type default)
			)
			(layer "F.Fab")
		)
		(fp_line
			(start 0.120396 0.2794)
			(end -0.12065 0.2794)
			(stroke
				(width 0.1)
				(type default)
			)
			(layer "F.Fab")
		)
		(fp_line
			(start -0.12065 0.3048)
			(end -0.67945 0.3048)
			(stroke
				(width 0.1)
				(type default)
			)
			(layer "F.Fab")
		)
		(fp_line
			(start -0.12065 0.2794)
			(end -0.12065 0.3048)
			(stroke
				(width 0.1)
				(type default)
			)
			(layer "F.Fab")
		)
		(fp_line
			(start -0.12065 -0.2794)
			(end 0.12065 -0.2794)
			(stroke
				(width 0.1)
				(type default)
			)
			(layer "F.Fab")
		)
		(fp_line
			(start -0.12065 -0.305054)
			(end -0.12065 -0.2794)
			(stroke
				(width 0.1)
				(type default)
			)
			(layer "F.Fab")
		)
		(fp_line
			(start -0.67945 0.3048)
			(end -0.67945 -0.305054)
			(stroke
				(width 0.1)
				(type default)
			)
			(layer "F.Fab")
		)
		(fp_line
			(start -0.67945 -0.305054)
			(end -0.12065 -0.305054)
			(stroke
				(width 0.1)
				(type default)
			)
			(layer "F.Fab")
		)
		(pad "1" smd circle
			(at -0.40005 0 180)
			(size 0 0)
			(layers "F.Cu" "F.Mask" "F.Paste")
			(net "PRSNT_CABLE_SWB_B1_ISO_N")
		)
		(pad "2" smd circle
			(at 0.40005 0 180)
			(size 0 0)
			(layers "F.Cu" "F.Mask" "F.Paste")
			(net "PRSNT_CABLE_SWB_B1_ISO_R_N")
		)
	)
)
